# SCM (Grand Teton) — schematic netlist excerpt (pin names and nets, part order shuffled) for the footprints in the layout excerpt that follows; sources: Cadence DE-HDL packaged netlist, KiCad conversion of 12092022_DA0F0TMDCD0_F0T_Management_Board_D_brd_V3_OCP.brd

H2B2  HOLE  EMPTY  pkg TH  page 57 : \1\ = NC
R831  Q_RES  15K 1% CHIP  pkg 0402LF  page 54 : A = P1V8_AUX ; B = U41_ADJ

(kicad_pcb
	(version 20260206)
	(generator "pcbnew")
	(generator_version "10.0")
	(general
		(thickness 1.6)
		(legacy_teardrops no)
	)
	(paper "A4")
	(title_block
		(title "12092022_DA0F0TMDCD0_F0T_Management_Board_D_brd_V3_OCP.brd")
		(comment 1 "Grand Teton / footprints 85-86 of 1440")
	)
	(layers
		(0 "F.Cu" signal "TOP")
		(4 "In1.Cu" signal "GND")
		(6 "In2.Cu" signal "IN1")
		(8 "In3.Cu" signal "GND1")
		(10 "In4.Cu" signal "IN2")
		(12 "In5.Cu" signal "VCC")
		(14 "In6.Cu" signal "VCC1")
		(16 "In7.Cu" signal "IN3")
		(18 "In8.Cu" signal "GND2")
		(20 "In9.Cu" signal "IN4")
		(22 "In10.Cu" signal "GND3")
		(2 "B.Cu" signal "BOTTOM")
		(9 "F.Adhes" user "F.Adhesive")
		(11 "B.Adhes" user "B.Adhesive")
		(13 "F.Paste" user "Package Geometry/Pastemask Top")
		(15 "B.Paste" user "Package Geometry/Pastemask Bottom")
		(5 "F.SilkS" user "Ref Des/Silkscreen Top")
		(7 "B.SilkS" user "Ref Des/Silkscreen Bottom")
		(1 "F.Mask" user "Board Geometry/Soldermask Top")
		(3 "B.Mask" user "Board Geometry/Soldermask Bottom")
		(17 "Dwgs.User" user "User.Drawings")
		(19 "Cmts.User" user "User.Comments")
		(21 "Eco1.User" user "User.Eco1")
		(23 "Eco2.User" user "User.Eco2")
		(25 "Edge.Cuts" user "Board Geometry/Outline")
		(27 "Margin" user)
		(31 "F.CrtYd" user "Package Geometry/Place Bound Top")
		(29 "B.CrtYd" user "Package Geometry/Place Bound Bottom")
		(35 "F.Fab" user "Ref Des/Assembly Top")
		(33 "B.Fab" user "Ref Des/Assembly Bottom")
	)
	(footprint ""
		(layer "F.Cu")
		(at 6.9342 -17.3228 90)
		(property "Reference" "H2B2"
			(at -1.47447 -6.4262 0)
			(unlocked yes)
			(layer "F.SilkS")
			(effects
				(font
					(size 0.7874 0.5842)
					(thickness 0.1524)
				)
				(justify left)
			)
		)
		(property "Value" ""
			(at 0 0 90)
			(layer "F.Fab")
			(effects
				(font
					(size 1.27 1.27)
				)
			)
		)
		(duplicate_pad_numbers_are_jumpers no)
		(fp_arc
			(start -1.834134 -1.548384)
			(mid 0.134587 -2.396606)
			(end 1.995932 -1.333246)
			(stroke
				(width 0.1524)
				(type default)
			)
			(layer "F.SilkS")
		)
		(fp_arc
			(start 2.2479 0.841756)
			(mid 1.367667 1.972542)
			(end 0 2.4003)
			(stroke
				(width 0.1524)
				(type default)
			)
			(layer "F.SilkS")
		)
		(fp_arc
			(start 0 2.4003)
			(mid -1.444342 1.917049)
			(end -2.307082 0.661924)
			(stroke
				(width 0.1524)
				(type default)
			)
			(layer "F.SilkS")
		)
		(fp_arc
			(start 1.212596 -6.478778)
			(mid 1.432628 -6.433742)
			(end 1.651 -6.381242)
			(stroke
				(width 0.1524)
				(type default)
			)
			(layer "B.SilkS")
		)
		(fp_arc
			(start 5.66801 3.364484)
			(mid 3.261093 5.728087)
			(end 0 6.5913)
			(stroke
				(width 0.1524)
				(type default)
			)
			(layer "B.SilkS")
		)
		(fp_arc
			(start 0 6.5913)
			(mid -3.324795 5.691563)
			(end -5.74167 3.237484)
			(stroke
				(width 0.1524)
				(type default)
			)
			(layer "B.SilkS")
		)
		(fp_circle
			(center 0 0)
			(end 0 6.5913)
			(stroke
				(width 0.1)
				(type default)
			)
			(fill no)
			(layer "B.Fab")
		)
		(fp_circle
			(center 0 0)
			(end 0 2.4003)
			(stroke
				(width 0.1)
				(type default)
			)
			(fill no)
			(layer "F.Fab")
		)
		(pad "" np_thru_hole circle
			(at 0 0 90)
			(size 3.175 3.175)
			(drill 3.175)
			(layers "*.Cu" "*.Mask")
			(clearance 0.381)
			(thermal_gap 0.381)
		)
		(zone
			(layers "F.Cu" "B.Cu" "In1.Cu" "In2.Cu" "In3.Cu" "In4.Cu" "In5.Cu" "In6.Cu"
				"In7.Cu" "In8.Cu" "In9.Cu" "In10.Cu"
			)
			(hatch none 0.5)
			(connect_pads
				(clearance 0)
			)
			(min_thickness 0.25)
			(keepout
				(tracks not_allowed)
				(vias allowed)
				(pads allowed)
				(copperpour not_allowed)
				(footprints allowed)
			)
			(placement
				(enabled no)
				(sheetname "")
			)
			(fill
				(thermal_gap 0.5)
				(thermal_bridge_width 0.5)
				(island_removal_mode 0)
			)
			(polygon
				(pts
					(arc
						(start 9.0297 -17.3228)
						(mid 4.8387 -17.3228)
						(end 9.0297 -17.3228)
					)
				)
			)
		)
	)
	(footprint ""
		(layer "F.Cu")
		(at 39.631112 -55.427626 90)
		(property "Reference" "R831"
			(at 0 0 90)
			(layer "F.SilkS")
			(hide yes)
			(effects
				(font
					(size 1.27 1.27)
				)
			)
		)
		(property "Value" ""
			(at 0 0 90)
			(layer "F.Fab")
			(effects
				(font
					(size 1.27 1.27)
				)
			)
		)
		(duplicate_pad_numbers_are_jumpers no)
		(fp_line
			(start 0.7874 -0.4064)
			(end 0.7874 0.4064)
			(stroke
				(width 0.1524)
				(type default)
			)
			(layer "F.SilkS")
		)
		(fp_line
			(start -0.7874 -0.4064)
			(end 0.7874 -0.4064)
			(stroke
				(width 0.1524)
				(type default)
			)
			(layer "F.SilkS")
		)
		(fp_line
			(start 0.7874 0.4064)
			(end -0.7874 0.4064)
			(stroke
				(width 0.1524)
				(type default)
			)
			(layer "F.SilkS")
		)
		(fp_line
			(start -0.7874 0.4064)
			(end -0.7874 -0.4064)
			(stroke
				(width 0.1524)
				(type default)
			)
			(layer "F.SilkS")
		)
		(fp_line
			(start -0.12065 -0.305054)
			(end -0.12065 -0.2794)
			(stroke
				(width 0.1)
				(type default)
			)
			(layer "F.Fab")
		)
		(fp_line
			(start -0.67945 -0.305054)
			(end -0.12065 -0.305054)
			(stroke
				(width 0.1)
				(type default)
			)
			(layer "F.Fab")
		)
		(fp_line
			(start 0.67945 -0.3048)
			(end 0.67945 0.3048)
			(stroke
				(width 0.1)
				(type default)
			)
			(layer "F.Fab")
		)
		(fp_line
			(start 0.12065 -0.3048)
			(end 0.67945 -0.3048)
			(stroke
				(width 0.1)
				(type default)
			)
			(layer "F.Fab")
		)
		(fp_line
			(start 0.12065 -0.2794)
			(end 0.12065 -0.3048)
			(stroke
				(width 0.1)
				(type default)
			)
			(layer "F.Fab")
		)
		(fp_line
			(start -0.12065 -0.2794)
			(end 0.12065 -0.2794)
			(stroke
				(width 0.1)
				(type default)
			)
			(layer "F.Fab")
		)
		(fp_line
			(start 0.120396 0.2794)
			(end -0.12065 0.2794)
			(stroke
				(width 0.1)
				(type default)
			)
			(layer "F.Fab")
		)
		(fp_line
			(start -0.12065 0.2794)
			(end -0.12065 0.3048)
			(stroke
				(width 0.1)
				(type default)
			)
			(layer "F.Fab")
		)
		(fp_line
			(start 0.67945 0.3048)
			(end 0.120396 0.3048)
			(stroke
				(width 0.1)
				(type default)
			)
			(layer "F.Fab")
		)
		(fp_line
			(start 0.120396 0.3048)
			(end 0.120396 0.2794)
			(stroke
				(width 0.1)
				(type default)
			)
			(layer "F.Fab")
		)
		(fp_line
			(start -0.12065 0.3048)
			(end -0.67945 0.3048)
			(stroke
				(width 0.1)
				(type default)
			)
			(layer "F.Fab")
		)
		(fp_line
			(start -0.67945 0.3048)
			(end -0.67945 -0.305054)
			(stroke
				(width 0.1)
				(type default)
			)
			(layer "F.Fab")
		)
		(pad "1" smd circle
			(at -0.40005 0 90)
			(size 0 0)
			(layers "F.Cu" "F.Mask" "F.Paste")
			(net "P1V8_AUX")
		)
		(pad "2" smd circle
			(at 0.40005 0 90)
			(size 0 0)
			(layers "F.Cu" "F.Mask" "F.Paste")
			(net "U41_ADJ")
		)
	)
)
